# T6G (Grand Teton) — schematic netlist excerpt (pin names and nets, part order shuffled) for the footprints in the layout excerpt that follows; sources: Cadence DE-HDL packaged netlist, KiCad conversion of 04192023_DAF0TMB3IC0_F0TG_MB_C_brd_V02_OCP.brd

Y2  Q_XTAL_4P_13BI_24GND  48MHZ MISC  pkg X_4S_FL4000120_3-2X2-5  page 28
  X1  = XTAL_CPU0_X48M_X1
  G1  = GND
  X2  = XTAL_CPU0_X48M_X2_R
  G2  = GND

R4545  Q_RES  4.7K 5% CHIP  pkg 0402LF  page 124 : A = P3V3_AUX ; B = HGX_DETECT
C6741  Q_CAP_DIFFBUS  DIFF BUS_0.22UF 6.3V 20% X6S  pkg C0201  page 352 : \1\ = P5E_CPU1_P3_TX_BUF_C_DP<8> ; \2\ = P5E_CPU1_P3_TX_BUF_DP<8>

(kicad_pcb
	(version 20260206)
	(generator "pcbnew")
	(generator_version "10.0")
	(general
		(thickness 1.6)
		(legacy_teardrops no)
	)
	(paper "A4")
	(title_block
		(title "04192023_DAF0TMB3IC0_F0TG_MB_C_brd_V02_OCP.brd")
		(comment 1 "Grand Teton / footprints 6496-6498 of 8354")
	)
	(layers
		(0 "F.Cu" signal "TOP")
		(4 "In1.Cu" signal "GND")
		(6 "In2.Cu" signal "IN1")
		(8 "In3.Cu" signal "GND1")
		(10 "In4.Cu" signal "IN2")
		(12 "In5.Cu" signal "GND2")
		(14 "In6.Cu" signal "IN3")
		(16 "In7.Cu" signal "GND3")
		(18 "In8.Cu" signal "VCC")
		(20 "In9.Cu" signal "VCC1")
		(22 "In10.Cu" signal "GND4")
		(24 "In11.Cu" signal "IN4")
		(26 "In12.Cu" signal "GND5")
		(28 "In13.Cu" signal "IN5")
		(30 "In14.Cu" signal "GND6")
		(32 "In15.Cu" signal "IN6")
		(34 "In16.Cu" signal "GND7")
		(2 "B.Cu" signal "BOTTOM")
		(9 "F.Adhes" user "F.Adhesive")
		(11 "B.Adhes" user "B.Adhesive")
		(13 "F.Paste" user "Package Geometry/Pastemask Top")
		(15 "B.Paste" user "Package Geometry/Pastemask Bottom")
		(5 "F.SilkS" user "Ref Des/Silkscreen Top")
		(7 "B.SilkS" user "Ref Des/Silkscreen Bottom")
		(1 "F.Mask" user "Board Geometry/Soldermask Top")
		(3 "B.Mask" user "Board Geometry/Soldermask Bottom")
		(17 "Dwgs.User" user "User.Drawings")
		(19 "Cmts.User" user "User.Comments")
		(21 "Eco1.User" user "User.Eco1")
		(23 "Eco2.User" user "User.Eco2")
		(25 "Edge.Cuts" user "Board Geometry/Outline")
		(27 "Margin" user)
		(31 "F.CrtYd" user "Package Geometry/Place Bound Top")
		(29 "B.CrtYd" user "Package Geometry/Place Bound Bottom")
		(35 "F.Fab" user "Ref Des/Assembly Top")
		(33 "B.Fab" user "Ref Des/Assembly Bottom")
	)
	(footprint ""
		(layer "B.Cu")
		(at 397.332962 -316.652148 90)
		(property "Reference" "Y2"
			(at 2.936748 0.993648 0)
			(unlocked yes)
			(layer "B.SilkS")
			(effects
				(font
					(size 0.7874 0.5842)
					(thickness 0.1524)
				)
				(justify left mirror)
			)
		)
		(property "Value" ""
			(at 0 0 90)
			(layer "B.Fab")
			(effects
				(font
					(size 1.27 1.27)
				)
				(justify mirror)
			)
		)
		(duplicate_pad_numbers_are_jumpers no)
		(fp_line
			(start 1.538732 -1.937004)
			(end -1.538732 -1.937004)
			(stroke
				(width 0.1524)
				(type default)
			)
			(layer "B.SilkS")
		)
		(fp_line
			(start -1.538732 -1.937004)
			(end -1.538732 1.937004)
			(stroke
				(width 0.1524)
				(type default)
			)
			(layer "B.SilkS")
		)
		(fp_line
			(start 1.538732 1.937004)
			(end 1.538732 -1.937004)
			(stroke
				(width 0.1524)
				(type default)
			)
			(layer "B.SilkS")
		)
		(fp_line
			(start -1.538732 1.937004)
			(end 1.538732 1.937004)
			(stroke
				(width 0.1524)
				(type default)
			)
			(layer "B.SilkS")
		)
		(fp_poly
			(pts
				(xy 1.724406 -1.059942) (xy 2.5908 -1.493266) (xy 2.5908 -0.626872)
			)
			(stroke
				(width 0)
				(type default)
			)
			(fill yes)
			(layer "B.SilkS")
		)
		(fp_line
			(start 1.299972 -1.649984)
			(end -1.299972 -1.649984)
			(stroke
				(width 0.1)
				(type default)
			)
			(layer "B.Fab")
		)
		(fp_line
			(start -1.299972 -1.649984)
			(end -1.299972 1.649984)
			(stroke
				(width 0.1)
				(type default)
			)
			(layer "B.Fab")
		)
		(fp_line
			(start 1.299972 1.649984)
			(end 1.299972 -1.649984)
			(stroke
				(width 0.1)
				(type default)
			)
			(layer "B.Fab")
		)
		(fp_line
			(start -1.299972 1.649984)
			(end 1.299972 1.649984)
			(stroke
				(width 0.1)
				(type default)
			)
			(layer "B.Fab")
		)
		(fp_poly
			(pts
				(xy 2.5908 -0.626872) (xy 2.5908 -1.493266) (xy 1.724406 -1.059942)
			)
			(stroke
				(width 0)
				(type default)
			)
			(fill yes)
			(layer "B.Fab")
		)
		(pad "1" smd rect
			(at 0.8001 -1.059942 270)
			(size 1.2192 1.4986)
			(layers "B.Cu" "B.Mask" "B.Paste")
			(net "XTAL_CPU0_X48M_X1")
		)
		(pad "2" smd rect
			(at 0.8001 1.059942 270)
			(size 1.2192 1.4986)
			(layers "B.Cu" "B.Mask" "B.Paste")
			(net "GND")
		)
		(pad "3" smd rect
			(at -0.8001 1.059942 270)
			(size 1.2192 1.4986)
			(layers "B.Cu" "B.Mask" "B.Paste")
			(net "XTAL_CPU0_X48M_X2_R")
		)
		(pad "4" smd rect
			(at -0.8001 -1.059942 270)
			(size 1.2192 1.4986)
			(layers "B.Cu" "B.Mask" "B.Paste")
			(net "GND")
		)
	)
	(footprint ""
		(layer "B.Cu")
		(at 111.379 -416.941 180)
		(property "Reference" "R4545"
			(at 0 0 0)
			(layer "B.SilkS")
			(hide yes)
			(effects
				(font
					(size 1.27 1.27)
				)
				(justify mirror)
			)
		)
		(property "Value" ""
			(at 0 0 0)
			(layer "B.Fab")
			(effects
				(font
					(size 1.27 1.27)
				)
				(justify mirror)
			)
		)
		(duplicate_pad_numbers_are_jumpers no)
		(fp_line
			(start 0.7874 0.4064)
			(end 0.7874 -0.4064)
			(stroke
				(width 0.1524)
				(type default)
			)
			(layer "B.SilkS")
		)
		(fp_line
			(start 0.7874 -0.4064)
			(end -0.7874 -0.4064)
			(stroke
				(width 0.1524)
				(type default)
			)
			(layer "B.SilkS")
		)
		(fp_line
			(start -0.7874 0.4064)
			(end 0.7874 0.4064)
			(stroke
				(width 0.1524)
				(type default)
			)
			(layer "B.SilkS")
		)
		(fp_line
			(start -0.7874 -0.4064)
			(end -0.7874 0.4064)
			(stroke
				(width 0.1524)
				(type default)
			)
			(layer "B.SilkS")
		)
		(fp_line
			(start 0.67945 0.3048)
			(end 0.67945 -0.305054)
			(stroke
				(width 0.1)
				(type default)
			)
			(layer "B.Fab")
		)
		(fp_line
			(start 0.67945 -0.305054)
			(end 0.12065 -0.305054)
			(stroke
				(width 0.1)
				(type default)
			)
			(layer "B.Fab")
		)
		(fp_line
			(start 0.12065 0.3048)
			(end 0.67945 0.3048)
			(stroke
				(width 0.1)
				(type default)
			)
			(layer "B.Fab")
		)
		(fp_line
			(start 0.12065 0.2794)
			(end 0.12065 0.3048)
			(stroke
				(width 0.1)
				(type default)
			)
			(layer "B.Fab")
		)
		(fp_line
			(start 0.12065 -0.2794)
			(end -0.12065 -0.2794)
			(stroke
				(width 0.1)
				(type default)
			)
			(layer "B.Fab")
		)
		(fp_line
			(start 0.12065 -0.305054)
			(end 0.12065 -0.2794)
			(stroke
				(width 0.1)
				(type default)
			)
			(layer "B.Fab")
		)
		(fp_line
			(start -0.120396 0.3048)
			(end -0.120396 0.2794)
			(stroke
				(width 0.1)
				(type default)
			)
			(layer "B.Fab")
		)
		(fp_line
			(start -0.120396 0.2794)
			(end 0.12065 0.2794)
			(stroke
				(width 0.1)
				(type default)
			)
			(layer "B.Fab")
		)
		(fp_line
			(start -0.12065 -0.2794)
			(end -0.12065 -0.3048)
			(stroke
				(width 0.1)
				(type default)
			)
			(layer "B.Fab")
		)
		(fp_line
			(start -0.12065 -0.3048)
			(end -0.67945 -0.3048)
			(stroke
				(width 0.1)
				(type default)
			)
			(layer "B.Fab")
		)
		(fp_line
			(start -0.67945 0.3048)
			(end -0.120396 0.3048)
			(stroke
				(width 0.1)
				(type default)
			)
			(layer "B.Fab")
		)
		(fp_line
			(start -0.67945 -0.3048)
			(end -0.67945 0.3048)
			(stroke
				(width 0.1)
				(type default)
			)
			(layer "B.Fab")
		)
		(pad "1" smd circle
			(at 0.40005 0)
			(size 0 0)
			(layers "B.Cu" "B.Mask" "B.Paste")
			(net "P3V3_AUX")
		)
		(pad "2" smd circle
			(at -0.40005 0)
			(size 0 0)
			(layers "B.Cu" "B.Mask" "B.Paste")
			(net "HGX_DETECT")
		)
	)
	(footprint ""
		(layer "B.Cu")
		(at 141.820646 -408.517344 90)
		(property "Reference" "C6741"
			(at 0 0 90)
			(layer "B.SilkS")
			(hide yes)
			(effects
				(font
					(size 1.27 1.27)
				)
				(justify mirror)
			)
		)
		(property "Value" ""
			(at 0 0 90)
			(layer "B.Fab")
			(effects
				(font
					(size 1.27 1.27)
				)
				(justify mirror)
			)
		)
		(duplicate_pad_numbers_are_jumpers no)
		(fp_line
			(start 0.299974 -0.150114)
			(end -0.299974 -0.150114)
			(stroke
				(width 0.1)
				(type default)
			)
			(layer "B.Fab")
		)
		(fp_line
			(start -0.299974 -0.150114)
			(end -0.299974 0.150114)
			(stroke
				(width 0.1)
				(type default)
			)
			(layer "B.Fab")
		)
		(fp_line
			(start 0.299974 0.150114)
			(end 0.299974 -0.150114)
			(stroke
				(width 0.1)
				(type default)
			)
			(layer "B.Fab")
		)
		(fp_line
			(start -0.299974 0.150114)
			(end 0.299974 0.150114)
			(stroke
				(width 0.1)
				(type default)
			)
			(layer "B.Fab")
		)
		(pad "1" smd rect
			(at 0.2667 0 270)
			(size 0.3048 0.381)
			(layers "B.Cu" "B.Mask" "B.Paste")
			(net "P5E_CPU1_P3_TX_BUF_C_DP<8>")
		)
		(pad "2" smd rect
			(at -0.2667 0 270)
			(size 0.3048 0.381)
			(layers "B.Cu" "B.Mask" "B.Paste")
			(net "P5E_CPU1_P3_TX_BUF_DP<8>")
		)
	)
)
